# T6G (Grand Teton) — schematic netlist excerpt (pin names and nets, part order shuffled) for the footprints in the layout excerpt that follows; sources: Cadence DE-HDL packaged netlist, KiCad conversion of 04192023_DAF0TMB3IC0_F0TG_MB_C_brd_V02_OCP.brd

PC2349  Q_CAP  1NF 50V 10% EMPTY  pkg 0402  page 264 : A = HSC_OCREF ; B = AGND_HSC
R1127  Q_RES  1K 1% CHIP  pkg 0201LF  page 311 : A = U17_E2 ; B = GND
PC2093  Q_CAP  1UF 25V 10% X6S  pkg C0402  page 134 : A = GND ; B = P3V3_OCP_REG_1

(kicad_pcb
	(version 20260206)
	(generator "pcbnew")
	(generator_version "10.0")
	(general
		(thickness 1.6)
		(legacy_teardrops no)
	)
	(paper "A4")
	(title_block
		(title "04192023_DAF0TMB3IC0_F0TG_MB_C_brd_V02_OCP.brd")
		(comment 1 "Grand Teton / footprints 2005-2007 of 8354")
	)
	(layers
		(0 "F.Cu" signal "TOP")
		(4 "In1.Cu" signal "GND")
		(6 "In2.Cu" signal "IN1")
		(8 "In3.Cu" signal "GND1")
		(10 "In4.Cu" signal "IN2")
		(12 "In5.Cu" signal "GND2")
		(14 "In6.Cu" signal "IN3")
		(16 "In7.Cu" signal "GND3")
		(18 "In8.Cu" signal "VCC")
		(20 "In9.Cu" signal "VCC1")
		(22 "In10.Cu" signal "GND4")
		(24 "In11.Cu" signal "IN4")
		(26 "In12.Cu" signal "GND5")
		(28 "In13.Cu" signal "IN5")
		(30 "In14.Cu" signal "GND6")
		(32 "In15.Cu" signal "IN6")
		(34 "In16.Cu" signal "GND7")
		(2 "B.Cu" signal "BOTTOM")
		(9 "F.Adhes" user "F.Adhesive")
		(11 "B.Adhes" user "B.Adhesive")
		(13 "F.Paste" user "Package Geometry/Pastemask Top")
		(15 "B.Paste" user "Package Geometry/Pastemask Bottom")
		(5 "F.SilkS" user "Ref Des/Silkscreen Top")
		(7 "B.SilkS" user "Ref Des/Silkscreen Bottom")
		(1 "F.Mask" user "Board Geometry/Soldermask Top")
		(3 "B.Mask" user "Board Geometry/Soldermask Bottom")
		(17 "Dwgs.User" user "User.Drawings")
		(19 "Cmts.User" user "User.Comments")
		(21 "Eco1.User" user "User.Eco1")
		(23 "Eco2.User" user "User.Eco2")
		(25 "Edge.Cuts" user "Board Geometry/Outline")
		(27 "Margin" user)
		(31 "F.CrtYd" user "Package Geometry/Place Bound Top")
		(29 "B.CrtYd" user "Package Geometry/Place Bound Bottom")
		(35 "F.Fab" user "Ref Des/Assembly Top")
		(33 "B.Fab" user "Ref Des/Assembly Bottom")
	)
	(footprint ""
		(layer "F.Cu")
		(at 376.33402 -423.904918 180)
		(property "Reference" "R1127"
			(at 0 0 180)
			(layer "F.SilkS")
			(hide yes)
			(effects
				(font
					(size 1.27 1.27)
				)
			)
		)
		(property "Value" ""
			(at 0 0 180)
			(layer "F.Fab")
			(effects
				(font
					(size 1.27 1.27)
				)
			)
		)
		(duplicate_pad_numbers_are_jumpers no)
		(fp_line
			(start 0.32512 0.175006)
			(end -0.32512 0.175006)
			(stroke
				(width 0.1)
				(type default)
			)
			(layer "F.Fab")
		)
		(fp_line
			(start 0.32512 -0.175006)
			(end 0.32512 0.175006)
			(stroke
				(width 0.1)
				(type default)
			)
			(layer "F.Fab")
		)
		(fp_line
			(start -0.32512 0.175006)
			(end -0.32512 -0.175006)
			(stroke
				(width 0.1)
				(type default)
			)
			(layer "F.Fab")
		)
		(fp_line
			(start -0.32512 -0.175006)
			(end 0.32512 -0.175006)
			(stroke
				(width 0.1)
				(type default)
			)
			(layer "F.Fab")
		)
		(pad "1" smd rect
			(at -0.2667 0 180)
			(size 0.3048 0.381)
			(layers "F.Cu" "F.Mask" "F.Paste")
			(net "U17_E2")
		)
		(pad "2" smd rect
			(at 0.2667 0)
			(size 0.3048 0.381)
			(layers "F.Cu" "F.Mask" "F.Paste")
			(net "GND")
		)
	)
	(footprint ""
		(layer "F.Cu")
		(at 226.0981 -398.940782 180)
		(property "Reference" "PC2349"
			(at 0 0 180)
			(layer "F.SilkS")
			(hide yes)
			(effects
				(font
					(size 1.27 1.27)
				)
			)
		)
		(property "Value" ""
			(at 0 0 180)
			(layer "F.Fab")
			(effects
				(font
					(size 1.27 1.27)
				)
			)
		)
		(duplicate_pad_numbers_are_jumpers no)
		(fp_line
			(start 0.7874 0.4064)
			(end -0.7874 0.4064)
			(stroke
				(width 0.1524)
				(type default)
			)
			(layer "F.SilkS")
		)
		(fp_line
			(start 0.7874 -0.4064)
			(end 0.7874 0.4064)
			(stroke
				(width 0.1524)
				(type default)
			)
			(layer "F.SilkS")
		)
		(fp_line
			(start -0.7874 0.4064)
			(end -0.7874 -0.4064)
			(stroke
				(width 0.1524)
				(type default)
			)
			(layer "F.SilkS")
		)
		(fp_line
			(start -0.7874 -0.4064)
			(end 0.7874 -0.4064)
			(stroke
				(width 0.1524)
				(type default)
			)
			(layer "F.SilkS")
		)
		(fp_line
			(start 0.67945 0.3048)
			(end 0.120396 0.3048)
			(stroke
				(width 0.1)
				(type default)
			)
			(layer "F.Fab")
		)
		(fp_line
			(start 0.67945 -0.3048)
			(end 0.67945 0.3048)
			(stroke
				(width 0.1)
				(type default)
			)
			(layer "F.Fab")
		)
		(fp_line
			(start 0.12065 -0.2794)
			(end 0.12065 -0.3048)
			(stroke
				(width 0.1)
				(type default)
			)
			(layer "F.Fab")
		)
		(fp_line
			(start 0.12065 -0.3048)
			(end 0.67945 -0.3048)
			(stroke
				(width 0.1)
				(type default)
			)
			(layer "F.Fab")
		)
		(fp_line
			(start 0.120396 0.3048)
			(end 0.120396 0.2794)
			(stroke
				(width 0.1)
				(type default)
			)
			(layer "F.Fab")
		)
		(fp_line
			(start 0.120396 0.2794)
			(end -0.12065 0.2794)
			(stroke
				(width 0.1)
				(type default)
			)
			(layer "F.Fab")
		)
		(fp_line
			(start -0.12065 0.3048)
			(end -0.67945 0.3048)
			(stroke
				(width 0.1)
				(type default)
			)
			(layer "F.Fab")
		)
		(fp_line
			(start -0.12065 0.2794)
			(end -0.12065 0.3048)
			(stroke
				(width 0.1)
				(type default)
			)
			(layer "F.Fab")
		)
		(fp_line
			(start -0.12065 -0.2794)
			(end 0.12065 -0.2794)
			(stroke
				(width 0.1)
				(type default)
			)
			(layer "F.Fab")
		)
		(fp_line
			(start -0.12065 -0.305054)
			(end -0.12065 -0.2794)
			(stroke
				(width 0.1)
				(type default)
			)
			(layer "F.Fab")
		)
		(fp_line
			(start -0.67945 0.3048)
			(end -0.67945 -0.305054)
			(stroke
				(width 0.1)
				(type default)
			)
			(layer "F.Fab")
		)
		(fp_line
			(start -0.67945 -0.305054)
			(end -0.12065 -0.305054)
			(stroke
				(width 0.1)
				(type default)
			)
			(layer "F.Fab")
		)
		(pad "1" smd circle
			(at -0.40005 0 180)
			(size 0 0)
			(layers "F.Cu" "F.Mask" "F.Paste")
			(net "HSC_OCREF")
		)
		(pad "2" smd circle
			(at 0.40005 0 180)
			(size 0 0)
			(layers "F.Cu" "F.Mask" "F.Paste")
			(net "AGND_HSC")
		)
	)
	(footprint ""
		(layer "F.Cu")
		(at 430.355756 -109.25937 -90)
		(property "Reference" "PC2093"
			(at 0 0 270)
			(layer "F.SilkS")
			(hide yes)
			(effects
				(font
					(size 1.27 1.27)
				)
			)
		)
		(property "Value" ""
			(at 0 0 270)
			(layer "F.Fab")
			(effects
				(font
					(size 1.27 1.27)
				)
			)
		)
		(duplicate_pad_numbers_are_jumpers no)
		(fp_line
			(start -0.7874 0.4064)
			(end -0.7874 -0.4064)
			(stroke
				(width 0.1524)
				(type default)
			)
			(layer "F.SilkS")
		)
		(fp_line
			(start 0.7874 0.4064)
			(end -0.7874 0.4064)
			(stroke
				(width 0.1524)
				(type default)
			)
			(layer "F.SilkS")
		)
		(fp_line
			(start -0.7874 -0.4064)
			(end 0.7874 -0.4064)
			(stroke
				(width 0.1524)
				(type default)
			)
			(layer "F.SilkS")
		)
		(fp_line
			(start 0.7874 -0.4064)
			(end 0.7874 0.4064)
			(stroke
				(width 0.1524)
				(type default)
			)
			(layer "F.SilkS")
		)
		(fp_line
			(start -0.67945 0.3048)
			(end -0.67945 -0.305054)
			(stroke
				(width 0.1)
				(type default)
			)
			(layer "F.Fab")
		)
		(fp_line
			(start -0.12065 0.3048)
			(end -0.67945 0.3048)
			(stroke
				(width 0.1)
				(type default)
			)
			(layer "F.Fab")
		)
		(fp_line
			(start 0.120396 0.3048)
			(end 0.120396 0.2794)
			(stroke
				(width 0.1)
				(type default)
			)
			(layer "F.Fab")
		)
		(fp_line
			(start 0.67945 0.3048)
			(end 0.120396 0.3048)
			(stroke
				(width 0.1)
				(type default)
			)
			(layer "F.Fab")
		)
		(fp_line
			(start -0.12065 0.2794)
			(end -0.12065 0.3048)
			(stroke
				(width 0.1)
				(type default)
			)
			(layer "F.Fab")
		)
		(fp_line
			(start 0.120396 0.2794)
			(end -0.12065 0.2794)
			(stroke
				(width 0.1)
				(type default)
			)
			(layer "F.Fab")
		)
		(fp_line
			(start -0.12065 -0.2794)
			(end 0.12065 -0.2794)
			(stroke
				(width 0.1)
				(type default)
			)
			(layer "F.Fab")
		)
		(fp_line
			(start 0.12065 -0.2794)
			(end 0.12065 -0.3048)
			(stroke
				(width 0.1)
				(type default)
			)
			(layer "F.Fab")
		)
		(fp_line
			(start 0.12065 -0.3048)
			(end 0.67945 -0.3048)
			(stroke
				(width 0.1)
				(type default)
			)
			(layer "F.Fab")
		)
		(fp_line
			(start 0.67945 -0.3048)
			(end 0.67945 0.3048)
			(stroke
				(width 0.1)
				(type default)
			)
			(layer "F.Fab")
		)
		(fp_line
			(start -0.67945 -0.305054)
			(end -0.12065 -0.305054)
			(stroke
				(width 0.1)
				(type default)
			)
			(layer "F.Fab")
		)
		(fp_line
			(start -0.12065 -0.305054)
			(end -0.12065 -0.2794)
			(stroke
				(width 0.1)
				(type default)
			)
			(layer "F.Fab")
		)
		(pad "1" smd circle
			(at -0.40005 0 270)
			(size 0 0)
			(layers "F.Cu" "F.Mask" "F.Paste")
			(net "GND")
		)
		(pad "2" smd circle
			(at 0.40005 0 270)
			(size 0 0)
			(layers "F.Cu" "F.Mask" "F.Paste")
			(net "P3V3_OCP_REG_1")
		)
	)
)
